(kicad_pcb
	(version 20260206)
	(generator "pcbnew")
	(generator_version "10.0")
	(general
		(thickness 1.6)
		(legacy_teardrops no)
	)
	(paper "A4")
	(title_block
		(title "01162023_DA0F0TEBIF0_F0T_Expander_BD_F_brd_V02_OCP.brd")
		(comment 1 "Grand Teton / footprints 9200-9208 of 9728")
	)
	(layers
		(0 "F.Cu" signal "TOP")
		(4 "In1.Cu" signal "GND")
		(6 "In2.Cu" signal "VCC")
		(8 "In3.Cu" signal "VCC1")
		(10 "In4.Cu" signal "GND1")
		(12 "In5.Cu" signal "IN1")
		(14 "In6.Cu" signal "GND2")
		(16 "In7.Cu" signal "IN2")
		(18 "In8.Cu" signal "GND3")
		(20 "In9.Cu" signal "IN3")
		(22 "In10.Cu" signal "GND4")
		(24 "In11.Cu" signal "IN4")
		(26 "In12.Cu" signal "GND5")
		(28 "In13.Cu" signal "IN5")
		(30 "In14.Cu" signal "GND6")
		(32 "In15.Cu" signal "IN6")
		(34 "In16.Cu" signal "GND7")
		(2 "B.Cu" signal "BOTTOM")
		(9 "F.Adhes" user "F.Adhesive")
		(11 "B.Adhes" user "B.Adhesive")
		(13 "F.Paste" user "Package Geometry/Pastemask Top")
		(15 "B.Paste" user "Package Geometry/Pastemask Bottom")
		(5 "F.SilkS" user "Ref Des/Silkscreen Top")
		(7 "B.SilkS" user "Ref Des/Silkscreen Bottom")
		(1 "F.Mask" user "Board Geometry/Soldermask Top")
		(3 "B.Mask" user "Board Geometry/Soldermask Bottom")
		(17 "Dwgs.User" user "User.Drawings")
		(19 "Cmts.User" user "User.Comments")
		(21 "Eco1.User" user "User.Eco1")
		(23 "Eco2.User" user "User.Eco2")
		(25 "Edge.Cuts" user "Board Geometry/Outline")
		(27 "Margin" user)
		(31 "F.CrtYd" user "Package Geometry/Place Bound Top")
		(29 "B.CrtYd" user "Package Geometry/Place Bound Bottom")
		(35 "F.Fab" user "Ref Des/Assembly Top")
		(33 "B.Fab" user "Ref Des/Assembly Bottom")
	)
	(footprint ""
		(layer "B.Cu")
		(at 107.839002 -308.580028 90)
		(property "Reference" "C4192"
			(at 0 0 90)
			(layer "B.SilkS")
			(hide yes)
			(effects
				(font
					(size 1.27 1.27)
				)
				(justify mirror)
			)
		)
		(property "Value" ""
			(at 0 0 90)
			(layer "B.Fab")
			(effects
				(font
					(size 1.27 1.27)
				)
				(justify mirror)
			)
		)
		(duplicate_pad_numbers_are_jumpers no)
		(fp_line
			(start 1.2954 -0.5842)
			(end -1.2954 -0.5842)
			(stroke
				(width 0.1524)
				(type default)
			)
			(layer "B.SilkS")
		)
		(fp_line
			(start -1.2954 -0.5842)
			(end -1.2954 0.5842)
			(stroke
				(width 0.1524)
				(type default)
			)
			(layer "B.SilkS")
		)
		(fp_line
			(start 1.2954 0.5842)
			(end 1.2954 -0.5842)
			(stroke
				(width 0.1524)
				(type default)
			)
			(layer "B.SilkS")
		)
		(fp_line
			(start -1.2954 0.5842)
			(end 1.2954 0.5842)
			(stroke
				(width 0.1524)
				(type default)
			)
			(layer "B.SilkS")
		)
		(fp_line
			(start 0.8636 -0.4572)
			(end -0.8636 -0.4572)
			(stroke
				(width 0.1)
				(type default)
			)
			(layer "B.Fab")
		)
		(fp_line
			(start -0.8636 -0.4572)
			(end -0.8636 -0.4064)
			(stroke
				(width 0.1)
				(type default)
			)
			(layer "B.Fab")
		)
		(fp_line
			(start 1.1938 -0.4064)
			(end 0.8636 -0.4064)
			(stroke
				(width 0.1)
				(type default)
			)
			(layer "B.Fab")
		)
		(fp_line
			(start 0.8636 -0.4064)
			(end 0.8636 -0.4572)
			(stroke
				(width 0.1)
				(type default)
			)
			(layer "B.Fab")
		)
		(fp_line
			(start -0.8636 -0.4064)
			(end -1.1938 -0.4064)
			(stroke
				(width 0.1)
				(type default)
			)
			(layer "B.Fab")
		)
		(fp_line
			(start -1.1938 -0.4064)
			(end -1.1938 0.4064)
			(stroke
				(width 0.1)
				(type default)
			)
			(layer "B.Fab")
		)
		(fp_line
			(start 1.1938 0.4064)
			(end 1.1938 -0.4064)
			(stroke
				(width 0.1)
				(type default)
			)
			(layer "B.Fab")
		)
		(fp_line
			(start 0.8636 0.4064)
			(end 1.1938 0.4064)
			(stroke
				(width 0.1)
				(type default)
			)
			(layer "B.Fab")
		)
		(fp_line
			(start -0.8636 0.4064)
			(end -0.8636 0.4572)
			(stroke
				(width 0.1)
				(type default)
			)
			(layer "B.Fab")
		)
		(fp_line
			(start -1.1938 0.4064)
			(end -0.8636 0.4064)
			(stroke
				(width 0.1)
				(type default)
			)
			(layer "B.Fab")
		)
		(fp_line
			(start 0.8636 0.4572)
			(end 0.8636 0.4064)
			(stroke
				(width 0.1)
				(type default)
			)
			(layer "B.Fab")
		)
		(fp_line
			(start -0.8636 0.4572)
			(end 0.8636 0.4572)
			(stroke
				(width 0.1)
				(type default)
			)
			(layer "B.Fab")
		)
		(pad "1" smd rect
			(at 0.7366 0)
			(size 0.7112 0.8128)
			(layers "B.Cu" "B.Mask" "B.Paste")
			(net "P0V8_PEX0")
		)
		(pad "2" smd rect
			(at -0.7366 0)
			(size 0.7112 0.8128)
			(layers "B.Cu" "B.Mask" "B.Paste")
			(net "GND")
		)
	)
	(footprint ""
		(layer "B.Cu")
		(at 248.421144 18.028412)
		(property "Reference" "DE02F_2"
			(at 2.784856 3.207258 0)
			(unlocked yes)
			(layer "B.SilkS")
			(effects
				(font
					(size 0.7874 0.5842)
					(thickness 0.1524)
				)
				(justify left mirror)
			)
		)
		(property "Value" ""
			(at 0 0 0)
			(layer "B.Fab")
			(effects
				(font
					(size 1.27 1.27)
				)
				(justify mirror)
			)
		)
		(duplicate_pad_numbers_are_jumpers no)
		(fp_line
			(start -1.2192 -2.1082)
			(end -1.2192 2.1082)
			(stroke
				(width 0.1524)
				(type default)
			)
			(layer "B.SilkS")
		)
		(fp_line
			(start -1.2192 2.1082)
			(end 1.2192 2.1082)
			(stroke
				(width 0.1524)
				(type default)
			)
			(layer "B.SilkS")
		)
		(fp_line
			(start 1.2192 -2.1082)
			(end -1.2192 -2.1082)
			(stroke
				(width 0.1524)
				(type default)
			)
			(layer "B.SilkS")
		)
		(fp_line
			(start 1.2192 2.1082)
			(end 1.2192 -2.1082)
			(stroke
				(width 0.1524)
				(type default)
			)
			(layer "B.SilkS")
		)
		(pad "" np_thru_hole circle
			(at -3.4671 -1.27 270)
			(size 1.0414 1.0414)
			(drill 1.0414)
			(layers "*.Cu" "*.Mask")
			(clearance 0.381)
			(thermal_gap 0.381)
		)
		(pad "" np_thru_hole circle
			(at -3.4671 1.27 270)
			(size 1.0414 1.0414)
			(drill 1.0414)
			(layers "*.Cu" "*.Mask")
			(clearance 0.381)
			(thermal_gap 0.381)
		)
		(pad "" np_thru_hole circle
			(at 2.8829 -1.27 270)
			(size 1.0414 1.0414)
			(drill 1.0414)
			(layers "*.Cu" "*.Mask")
			(clearance 0.381)
			(thermal_gap 0.381)
		)
		(pad "" np_thru_hole circle
			(at 2.8829 1.27 270)
			(size 1.0414 1.0414)
			(drill 1.0414)
			(layers "*.Cu" "*.Mask")
			(clearance 0.381)
			(thermal_gap 0.381)
		)
		(pad "1" smd rect
			(at -0.8255 -0.249936 270)
			(size 0.3048 0.508)
			(layers "B.Cu" "B.Mask" "B.Paste")
			(net "85_5INCH_BOTTOM_DP")
		)
		(pad "2" smd rect
			(at -0.8255 0.249936 270)
			(size 0.3048 0.508)
			(layers "B.Cu" "B.Mask" "B.Paste")
			(net "85_5INCH_BOTTOM_DN")
		)
		(pad "3" smd circle
			(at 0 0 180)
			(size 0 0)
			(layers "B.Cu" "B.Mask" "B.Paste")
			(net "COUPON_GND2")
		)
		(zone
			(layers "F.Cu" "B.Cu" "In1.Cu" "In2.Cu" "In3.Cu" "In4.Cu" "In5.Cu" "In6.Cu"
				"In7.Cu" "In8.Cu" "In9.Cu" "In10.Cu" "In11.Cu" "In12.Cu" "In13.Cu" "In14.Cu"
				"In15.Cu" "In16.Cu"
			)
			(hatch none 0.5)
			(connect_pads
				(clearance 0)
			)
			(min_thickness 0.25)
			(keepout
				(tracks not_allowed)
				(vias allowed)
				(pads allowed)
				(copperpour not_allowed)
				(footprints allowed)
			)
			(placement
				(enabled no)
				(sheetname "")
			)
			(fill
				(thermal_gap 0.5)
				(thermal_bridge_width 0.5)
				(island_removal_mode 0)
			)
			(polygon
				(pts
					(arc
						(start 245.881144 16.758412)
						(mid 244.026944 16.758412)
						(end 245.881144 16.758412)
					)
				)
			)
		)
		(zone
			(layers "F.Cu" "B.Cu" "In1.Cu" "In2.Cu" "In3.Cu" "In4.Cu" "In5.Cu" "In6.Cu"
				"In7.Cu" "In8.Cu" "In9.Cu" "In10.Cu" "In11.Cu" "In12.Cu" "In13.Cu" "In14.Cu"
				"In15.Cu" "In16.Cu"
			)
			(hatch none 0.5)
			(connect_pads
				(clearance 0)
			)
			(min_thickness 0.25)
			(keepout
				(tracks not_allowed)
				(vias allowed)
				(pads allowed)
				(copperpour not_allowed)
				(footprints allowed)
			)
			(placement
				(enabled no)
				(sheetname "")
			)
			(fill
				(thermal_gap 0.5)
				(thermal_bridge_width 0.5)
				(island_removal_mode 0)
			)
			(polygon
				(pts
					(arc
						(start 245.881144 19.298412)
						(mid 244.026944 19.298412)
						(end 245.881144 19.298412)
					)
				)
			)
		)
		(zone
			(layers "F.Cu" "B.Cu" "In1.Cu" "In2.Cu" "In3.Cu" "In4.Cu" "In5.Cu" "In6.Cu"
				"In7.Cu" "In8.Cu" "In9.Cu" "In10.Cu" "In11.Cu" "In12.Cu" "In13.Cu" "In14.Cu"
				"In15.Cu" "In16.Cu"
			)
			(hatch none 0.5)
			(connect_pads
				(clearance 0)
			)
			(min_thickness 0.25)
			(keepout
				(tracks not_allowed)
				(vias allowed)
				(pads allowed)
				(copperpour not_allowed)
				(footprints allowed)
			)
			(placement
				(enabled no)
				(sheetname "")
			)
			(fill
				(thermal_gap 0.5)
				(thermal_bridge_width 0.5)
				(island_removal_mode 0)
			)
			(polygon
				(pts
					(arc
						(start 252.231144 16.758412)
						(mid 250.376944 16.758412)
						(end 252.231144 16.758412)
					)
				)
			)
		)
		(zone
			(layers "F.Cu" "B.Cu" "In1.Cu" "In2.Cu" "In3.Cu" "In4.Cu" "In5.Cu" "In6.Cu"
				"In7.Cu" "In8.Cu" "In9.Cu" "In10.Cu" "In11.Cu" "In12.Cu" "In13.Cu" "In14.Cu"
				"In15.Cu" "In16.Cu"
			)
			(hatch none 0.5)
			(connect_pads
				(clearance 0)
			)
			(min_thickness 0.25)
			(keepout
				(tracks not_allowed)
				(vias allowed)
				(pads allowed)
				(copperpour not_allowed)
				(footprints allowed)
			)
			(placement
				(enabled no)
				(sheetname "")
			)
			(fill
				(thermal_gap 0.5)
				(thermal_bridge_width 0.5)
				(island_removal_mode 0)
			)
			(polygon
				(pts
					(arc
						(start 252.231144 19.298412)
						(mid 250.376944 19.298412)
						(end 252.231144 19.298412)
					)
				)
			)
		)
		(zone
			(layer "B.Cu")
			(hatch none 0.5)
			(connect_pads
				(clearance 0)
			)
			(min_thickness 0.25)
			(keepout
				(tracks not_allowed)
				(vias allowed)
				(pads allowed)
				(copperpour not_allowed)
				(footprints allowed)
			)
			(placement
				(enabled no)
				(sheetname "")
			)
			(fill
				(thermal_gap 0.5)
				(thermal_bridge_width 0.5)
				(island_removal_mode 0)
			)
			(polygon
				(pts
					(xy 247.303544 17.479772) (xy 247.303544 17.575276) (xy 247.900444 17.575276) (xy 247.900444 17.981676)
					(xy 247.303544 17.981676) (xy 247.303544 18.075148) (xy 247.900444 18.075148) (xy 247.900444 18.481548)
					(xy 247.303544 18.481548) (xy 247.303544 18.577052) (xy 248.002044 18.577052) (xy 248.002044 17.479772)
				)
			)
		)
	)
	(footprint ""
		(layer "B.Cu")
		(at 66.299842 -288.299906 90)
		(property "Reference" "C2940"
			(at 0 0 90)
			(layer "B.SilkS")
			(hide yes)
			(effects
				(font
					(size 1.27 1.27)
				)
				(justify mirror)
			)
		)
		(property "Value" ""
			(at 0 0 90)
			(layer "B.Fab")
			(effects
				(font
					(size 1.27 1.27)
				)
				(justify mirror)
			)
		)
		(duplicate_pad_numbers_are_jumpers no)
		(fp_line
			(start 0.299974 -0.150114)
			(end -0.299974 -0.150114)
			(stroke
				(width 0.1)
				(type default)
			)
			(layer "B.Fab")
		)
		(fp_line
			(start -0.299974 -0.150114)
			(end -0.299974 0.150114)
			(stroke
				(width 0.1)
				(type default)
			)
			(layer "B.Fab")
		)
		(fp_line
			(start 0.299974 0.150114)
			(end 0.299974 -0.150114)
			(stroke
				(width 0.1)
				(type default)
			)
			(layer "B.Fab")
		)
		(fp_line
			(start -0.299974 0.150114)
			(end 0.299974 0.150114)
			(stroke
				(width 0.1)
				(type default)
			)
			(layer "B.Fab")
		)
		(pad "1" smd rect
			(at 0.2667 0 270)
			(size 0.3048 0.381)
			(layers "B.Cu" "B.Mask" "B.Paste")
			(net "P1V25_PEX0")
		)
		(pad "2" smd rect
			(at -0.2667 0 270)
			(size 0.3048 0.381)
			(layers "B.Cu" "B.Mask" "B.Paste")
			(net "GND")
		)
	)
	(footprint ""
		(layer "B.Cu")
		(at 65.349882 -301.599854 -90)
		(property "Reference" "C1193"
			(at 0 0 90)
			(layer "B.SilkS")
			(hide yes)
			(effects
				(font
					(size 1.27 1.27)
				)
				(justify mirror)
			)
		)
		(property "Value" ""
			(at 0 0 90)
			(layer "B.Fab")
			(effects
				(font
					(size 1.27 1.27)
				)
				(justify mirror)
			)
		)
		(duplicate_pad_numbers_are_jumpers no)
		(fp_line
			(start -0.299974 0.150114)
			(end 0.299974 0.150114)
			(stroke
				(width 0.1)
				(type default)
			)
			(layer "B.Fab")
		)
		(fp_line
			(start 0.299974 0.150114)
			(end 0.299974 -0.150114)
			(stroke
				(width 0.1)
				(type default)
			)
			(layer "B.Fab")
		)
		(fp_line
			(start -0.299974 -0.150114)
			(end -0.299974 0.150114)
			(stroke
				(width 0.1)
				(type default)
			)
			(layer "B.Fab")
		)
		(fp_line
			(start 0.299974 -0.150114)
			(end -0.299974 -0.150114)
			(stroke
				(width 0.1)
				(type default)
			)
			(layer "B.Fab")
		)
		(pad "1" smd rect
			(at 0.2667 0 90)
			(size 0.3048 0.381)
			(layers "B.Cu" "B.Mask" "B.Paste")
			(net "P0V8_SERDES_VDDA_PEX0")
		)
		(pad "2" smd rect
			(at -0.2667 0 90)
			(size 0.3048 0.381)
			(layers "B.Cu" "B.Mask" "B.Paste")
			(net "GND")
		)
	)
	(footprint ""
		(layer "B.Cu")
		(at 342.894158 -218.787218 -90)
		(property "Reference" "C2068"
			(at 0 0 90)
			(layer "B.SilkS")
			(hide yes)
			(effects
				(font
					(size 1.27 1.27)
				)
				(justify mirror)
			)
		)
		(property "Value" ""
			(at 0 0 90)
			(layer "B.Fab")
			(effects
				(font
					(size 1.27 1.27)
				)
				(justify mirror)
			)
		)
		(duplicate_pad_numbers_are_jumpers no)
		(fp_line
			(start -0.69215 0.2921)
			(end 0.69215 0.2921)
			(stroke
				(width 0.1524)
				(type default)
			)
			(layer "B.SilkS")
		)
		(fp_line
			(start 0.69215 0.2921)
			(end 0.69215 -0.2921)
			(stroke
				(width 0.1524)
				(type default)
			)
			(layer "B.SilkS")
		)
		(fp_line
			(start -0.69215 -0.2921)
			(end -0.69215 0.2921)
			(stroke
				(width 0.1524)
				(type default)
			)
			(layer "B.SilkS")
		)
		(fp_line
			(start 0.69215 -0.2921)
			(end -0.69215 -0.2921)
			(stroke
				(width 0.1524)
				(type default)
			)
			(layer "B.SilkS")
		)
		(fp_line
			(start -0.51435 0.2794)
			(end 0.51435 0.2794)
			(stroke
				(width 0.1)
				(type default)
			)
			(layer "B.Fab")
		)
		(fp_line
			(start 0.51435 0.2794)
			(end 0.51435 -0.2794)
			(stroke
				(width 0.1)
				(type default)
			)
			(layer "B.Fab")
		)
		(fp_line
			(start -0.51435 -0.2794)
			(end -0.51435 0.2794)
			(stroke
				(width 0.1)
				(type default)
			)
			(layer "B.Fab")
		)
		(fp_line
			(start 0.51435 -0.2794)
			(end -0.51435 -0.2794)
			(stroke
				(width 0.1)
				(type default)
			)
			(layer "B.Fab")
		)
		(pad "1" smd circle
			(at 0.40005 0 90)
			(size 0 0)
			(layers "B.Cu" "B.Mask" "B.Paste")
			(net "P3V3_VCC_FPGA_CORE")
		)
		(pad "2" smd circle
			(at -0.40005 0 90)
			(size 0 0)
			(layers "B.Cu" "B.Mask" "B.Paste")
			(net "GND")
		)
		(zone
			(layer "B.Cu")
			(hatch none 0.5)
			(connect_pads
				(clearance 0)
			)
			(min_thickness 0.25)
			(keepout
				(tracks not_allowed)
				(vias allowed)
				(pads allowed)
				(copperpour not_allowed)
				(footprints allowed)
			)
			(placement
				(enabled no)
				(sheetname "")
			)
			(fill
				(thermal_gap 0.5)
				(thermal_bridge_width 0.5)
				(island_removal_mode 0)
			)
			(polygon
				(pts
					(xy 342.806528 -218.596718) (xy 342.748362 -218.688158) (xy 342.748362 -218.887548) (xy 342.806528 -218.977718)
					(xy 342.981788 -218.977718) (xy 343.040208 -218.887548) (xy 343.040208 -218.688158) (xy 342.982042 -218.596718)
				)
			)
		)
	)
	(footprint ""
		(layer "B.Cu")
		(at 180.02504 -305.399948 -90)
		(property "Reference" "C3127"
			(at 0 0 90)
			(layer "B.SilkS")
			(hide yes)
			(effects
				(font
					(size 1.27 1.27)
				)
				(justify mirror)
			)
		)
		(property "Value" ""
			(at 0 0 90)
			(layer "B.Fab")
			(effects
				(font
					(size 1.27 1.27)
				)
				(justify mirror)
			)
		)
		(duplicate_pad_numbers_are_jumpers no)
		(fp_line
			(start -0.299974 0.150114)
			(end 0.299974 0.150114)
			(stroke
				(width 0.1)
				(type default)
			)
			(layer "B.Fab")
		)
		(fp_line
			(start 0.299974 0.150114)
			(end 0.299974 -0.150114)
			(stroke
				(width 0.1)
				(type default)
			)
			(layer "B.Fab")
		)
		(fp_line
			(start -0.299974 -0.150114)
			(end -0.299974 0.150114)
			(stroke
				(width 0.1)
				(type default)
			)
			(layer "B.Fab")
		)
		(fp_line
			(start 0.299974 -0.150114)
			(end -0.299974 -0.150114)
			(stroke
				(width 0.1)
				(type default)
			)
			(layer "B.Fab")
		)
		(pad "1" smd rect
			(at 0.2667 0 90)
			(size 0.3048 0.381)
			(layers "B.Cu" "B.Mask" "B.Paste")
			(net "P1V25_SERDES_VDDPLL_PEX1")
		)
		(pad "2" smd rect
			(at -0.2667 0 90)
			(size 0.3048 0.381)
			(layers "B.Cu" "B.Mask" "B.Paste")
			(net "GND")
		)
	)
	(footprint ""
		(layer "B.Cu")
		(at 293.74973 -303.499774 -90)
		(property "Reference" "C3256"
			(at 0 0 90)
			(layer "B.SilkS")
			(hide yes)
			(effects
				(font
					(size 1.27 1.27)
				)
				(justify mirror)
			)
		)
		(property "Value" ""
			(at 0 0 90)
			(layer "B.Fab")
			(effects
				(font
					(size 1.27 1.27)
				)
				(justify mirror)
			)
		)
		(duplicate_pad_numbers_are_jumpers no)
		(fp_line
			(start -0.299974 0.150114)
			(end 0.299974 0.150114)
			(stroke
				(width 0.1)
				(type default)
			)
			(layer "B.Fab")
		)
		(fp_line
			(start 0.299974 0.150114)
			(end 0.299974 -0.150114)
			(stroke
				(width 0.1)
				(type default)
			)
			(layer "B.Fab")
		)
		(fp_line
			(start -0.299974 -0.150114)
			(end -0.299974 0.150114)
			(stroke
				(width 0.1)
				(type default)
			)
			(layer "B.Fab")
		)
		(fp_line
			(start 0.299974 -0.150114)
			(end -0.299974 -0.150114)
			(stroke
				(width 0.1)
				(type default)
			)
			(layer "B.Fab")
		)
		(pad "1" smd rect
			(at 0.2667 0 90)
			(size 0.3048 0.381)
			(layers "B.Cu" "B.Mask" "B.Paste")
			(net "P1V25_PEX2")
		)
		(pad "2" smd rect
			(at -0.2667 0 90)
			(size 0.3048 0.381)
			(layers "B.Cu" "B.Mask" "B.Paste")
			(net "GND")
		)
	)
	(footprint ""
		(layer "B.Cu")
		(at 134.292594 -327.3552)
		(property "Reference" "PJ21"
			(at 0 0 0)
			(layer "B.SilkS")
			(hide yes)
			(effects
				(font
					(size 1.27 1.27)
				)
				(justify mirror)
			)
		)
		(property "Value" ""
			(at 0 0 0)
			(layer "B.Fab")
			(effects
				(font
					(size 1.27 1.27)
				)
				(justify mirror)
			)
		)
		(duplicate_pad_numbers_are_jumpers no)
		(pad "1" smd circle
			(at 0.40005 0 90)
			(size 0 0)
			(layers "B.Cu" "B.Mask" "B.Paste")
			(net "VSENSE_P0V8_PEX1_SKT_VRTN")
		)
		(pad "2" smd rect
			(at -0.40005 0)
			(size 0.4572 0.508)
			(layers "B.Cu" "B.Mask" "B.Paste")
			(net "SH_P0V8_PEX1_RGND1")
		)
		(zone
			(layer "B.Cu")
			(hatch none 0.5)
			(connect_pads
				(clearance 0)
			)
			(min_thickness 0.25)
			(keepout
				(tracks allowed)
				(vias not_allowed)
				(pads allowed)
				(copperpour not_allowed)
				(footprints allowed)
			)
			(placement
				(enabled no)
				(sheetname "")
			)
			(fill
				(thermal_gap 0.5)
				(thermal_bridge_width 0.5)
				(island_removal_mode 0)
			)
			(polygon
				(pts
					(xy 133.606794 -327.0504) (xy 133.606794 -327.66) (xy 134.978394 -327.66) (xy 134.978394 -327.0504)
				)
			)
		)
	)
	(footprint ""
		(layer "B.Cu")
		(at 414.124902 -293.99992 -90)
		(property "Reference" "C1900"
			(at 0 0 90)
			(layer "B.SilkS")
			(hide yes)
			(effects
				(font
					(size 1.27 1.27)
				)
				(justify mirror)
			)
		)
		(property "Value" ""
			(at 0 0 90)
			(layer "B.Fab")
			(effects
				(font
					(size 1.27 1.27)
				)
				(justify mirror)
			)
		)
		(duplicate_pad_numbers_are_jumpers no)
		(fp_line
			(start -0.299974 0.150114)
			(end 0.299974 0.150114)
			(stroke
				(width 0.1)
				(type default)
			)
			(layer "B.Fab")
		)
		(fp_line
			(start 0.299974 0.150114)
			(end 0.299974 -0.150114)
			(stroke
				(width 0.1)
				(type default)
			)
			(layer "B.Fab")
		)
		(fp_line
			(start -0.299974 -0.150114)
			(end -0.299974 0.150114)
			(stroke
				(width 0.1)
				(type default)
			)
			(layer "B.Fab")
		)
		(fp_line
			(start 0.299974 -0.150114)
			(end -0.299974 -0.150114)
			(stroke
				(width 0.1)
				(type default)
			)
			(layer "B.Fab")
		)
		(pad "1" smd rect
			(at 0.2667 0 90)
			(size 0.3048 0.381)
			(layers "B.Cu" "B.Mask" "B.Paste")
			(net "P0V8_PEX3")
		)
		(pad "2" smd rect
			(at -0.2667 0 90)
			(size 0.3048 0.381)
			(layers "B.Cu" "B.Mask" "B.Paste")
			(net "GND")
		)
	)
)
